(kicad_pcb
	(version 20260206)
	(generator "pcbnew")
	(generator_version "10.0")
	(general
		(thickness 1.6)
		(legacy_teardrops no)
	)
	(paper "A4")
	(title_block
		(title "01162023_DA0F0TEBIF0_F0T_Expander_BD_F_brd_V02_OCP.brd")
		(comment 1 "Grand Teton / footprints 8733-8741 of 9728")
	)
	(layers
		(0 "F.Cu" signal "TOP")
		(4 "In1.Cu" signal "GND")
		(6 "In2.Cu" signal "VCC")
		(8 "In3.Cu" signal "VCC1")
		(10 "In4.Cu" signal "GND1")
		(12 "In5.Cu" signal "IN1")
		(14 "In6.Cu" signal "GND2")
		(16 "In7.Cu" signal "IN2")
		(18 "In8.Cu" signal "GND3")
		(20 "In9.Cu" signal "IN3")
		(22 "In10.Cu" signal "GND4")
		(24 "In11.Cu" signal "IN4")
		(26 "In12.Cu" signal "GND5")
		(28 "In13.Cu" signal "IN5")
		(30 "In14.Cu" signal "GND6")
		(32 "In15.Cu" signal "IN6")
		(34 "In16.Cu" signal "GND7")
		(2 "B.Cu" signal "BOTTOM")
		(9 "F.Adhes" user "F.Adhesive")
		(11 "B.Adhes" user "B.Adhesive")
		(13 "F.Paste" user "Package Geometry/Pastemask Top")
		(15 "B.Paste" user "Package Geometry/Pastemask Bottom")
		(5 "F.SilkS" user "Ref Des/Silkscreen Top")
		(7 "B.SilkS" user "Ref Des/Silkscreen Bottom")
		(1 "F.Mask" user "Board Geometry/Soldermask Top")
		(3 "B.Mask" user "Board Geometry/Soldermask Bottom")
		(17 "Dwgs.User" user "User.Drawings")
		(19 "Cmts.User" user "User.Comments")
		(21 "Eco1.User" user "User.Eco1")
		(23 "Eco2.User" user "User.Eco2")
		(25 "Edge.Cuts" user "Board Geometry/Outline")
		(27 "Margin" user)
		(31 "F.CrtYd" user "Package Geometry/Place Bound Top")
		(29 "B.CrtYd" user "Package Geometry/Place Bound Bottom")
		(35 "F.Fab" user "Ref Des/Assembly Top")
		(33 "B.Fab" user "Ref Des/Assembly Bottom")
	)
	(footprint ""
		(layer "B.Cu")
		(at 181.92496 -305.399948 -90)
		(property "Reference" "C3129"
			(at 0 0 90)
			(layer "B.SilkS")
			(hide yes)
			(effects
				(font
					(size 1.27 1.27)
				)
				(justify mirror)
			)
		)
		(property "Value" ""
			(at 0 0 90)
			(layer "B.Fab")
			(effects
				(font
					(size 1.27 1.27)
				)
				(justify mirror)
			)
		)
		(duplicate_pad_numbers_are_jumpers no)
		(fp_line
			(start -0.299974 0.150114)
			(end 0.299974 0.150114)
			(stroke
				(width 0.1)
				(type default)
			)
			(layer "B.Fab")
		)
		(fp_line
			(start 0.299974 0.150114)
			(end 0.299974 -0.150114)
			(stroke
				(width 0.1)
				(type default)
			)
			(layer "B.Fab")
		)
		(fp_line
			(start -0.299974 -0.150114)
			(end -0.299974 0.150114)
			(stroke
				(width 0.1)
				(type default)
			)
			(layer "B.Fab")
		)
		(fp_line
			(start 0.299974 -0.150114)
			(end -0.299974 -0.150114)
			(stroke
				(width 0.1)
				(type default)
			)
			(layer "B.Fab")
		)
		(pad "1" smd rect
			(at 0.2667 0 90)
			(size 0.3048 0.381)
			(layers "B.Cu" "B.Mask" "B.Paste")
			(net "P1V25_SERDES_VDDPLL_PEX1")
		)
		(pad "2" smd rect
			(at -0.2667 0 90)
			(size 0.3048 0.381)
			(layers "B.Cu" "B.Mask" "B.Paste")
			(net "GND")
		)
	)
	(footprint ""
		(layer "B.Cu")
		(at 406.524968 -293.99992 90)
		(property "Reference" "C1908"
			(at 0 0 90)
			(layer "B.SilkS")
			(hide yes)
			(effects
				(font
					(size 1.27 1.27)
				)
				(justify mirror)
			)
		)
		(property "Value" ""
			(at 0 0 90)
			(layer "B.Fab")
			(effects
				(font
					(size 1.27 1.27)
				)
				(justify mirror)
			)
		)
		(duplicate_pad_numbers_are_jumpers no)
		(fp_line
			(start 0.299974 -0.150114)
			(end -0.299974 -0.150114)
			(stroke
				(width 0.1)
				(type default)
			)
			(layer "B.Fab")
		)
		(fp_line
			(start -0.299974 -0.150114)
			(end -0.299974 0.150114)
			(stroke
				(width 0.1)
				(type default)
			)
			(layer "B.Fab")
		)
		(fp_line
			(start 0.299974 0.150114)
			(end 0.299974 -0.150114)
			(stroke
				(width 0.1)
				(type default)
			)
			(layer "B.Fab")
		)
		(fp_line
			(start -0.299974 0.150114)
			(end 0.299974 0.150114)
			(stroke
				(width 0.1)
				(type default)
			)
			(layer "B.Fab")
		)
		(pad "1" smd rect
			(at 0.2667 0 270)
			(size 0.3048 0.381)
			(layers "B.Cu" "B.Mask" "B.Paste")
			(net "P0V8_PEX3")
		)
		(pad "2" smd rect
			(at -0.2667 0 270)
			(size 0.3048 0.381)
			(layers "B.Cu" "B.Mask" "B.Paste")
			(net "GND")
		)
	)
	(footprint ""
		(layer "B.Cu")
		(at 168.625012 -286.399732 90)
		(property "Reference" "C3146"
			(at 0 0 90)
			(layer "B.SilkS")
			(hide yes)
			(effects
				(font
					(size 1.27 1.27)
				)
				(justify mirror)
			)
		)
		(property "Value" ""
			(at 0 0 90)
			(layer "B.Fab")
			(effects
				(font
					(size 1.27 1.27)
				)
				(justify mirror)
			)
		)
		(duplicate_pad_numbers_are_jumpers no)
		(fp_line
			(start 0.299974 -0.150114)
			(end -0.299974 -0.150114)
			(stroke
				(width 0.1)
				(type default)
			)
			(layer "B.Fab")
		)
		(fp_line
			(start -0.299974 -0.150114)
			(end -0.299974 0.150114)
			(stroke
				(width 0.1)
				(type default)
			)
			(layer "B.Fab")
		)
		(fp_line
			(start 0.299974 0.150114)
			(end 0.299974 -0.150114)
			(stroke
				(width 0.1)
				(type default)
			)
			(layer "B.Fab")
		)
		(fp_line
			(start -0.299974 0.150114)
			(end 0.299974 0.150114)
			(stroke
				(width 0.1)
				(type default)
			)
			(layer "B.Fab")
		)
		(pad "1" smd rect
			(at 0.2667 0 270)
			(size 0.3048 0.381)
			(layers "B.Cu" "B.Mask" "B.Paste")
			(net "P1V25_SERDES_VDDPLL_PEX1")
		)
		(pad "2" smd rect
			(at -0.2667 0 270)
			(size 0.3048 0.381)
			(layers "B.Cu" "B.Mask" "B.Paste")
			(net "GND")
		)
	)
	(footprint ""
		(layer "B.Cu")
		(at 364.807754 -324.163944 -90)
		(property "Reference" "C4370"
			(at 0 0 90)
			(layer "B.SilkS")
			(hide yes)
			(effects
				(font
					(size 1.27 1.27)
				)
				(justify mirror)
			)
		)
		(property "Value" ""
			(at 0 0 90)
			(layer "B.Fab")
			(effects
				(font
					(size 1.27 1.27)
				)
				(justify mirror)
			)
		)
		(duplicate_pad_numbers_are_jumpers no)
		(fp_line
			(start -1.2954 0.5842)
			(end 1.2954 0.5842)
			(stroke
				(width 0.1524)
				(type default)
			)
			(layer "B.SilkS")
		)
		(fp_line
			(start 1.2954 0.5842)
			(end 1.2954 -0.5842)
			(stroke
				(width 0.1524)
				(type default)
			)
			(layer "B.SilkS")
		)
		(fp_line
			(start -1.2954 -0.5842)
			(end -1.2954 0.5842)
			(stroke
				(width 0.1524)
				(type default)
			)
			(layer "B.SilkS")
		)
		(fp_line
			(start 1.2954 -0.5842)
			(end -1.2954 -0.5842)
			(stroke
				(width 0.1524)
				(type default)
			)
			(layer "B.SilkS")
		)
		(fp_line
			(start -0.8636 0.4572)
			(end 0.8636 0.4572)
			(stroke
				(width 0.1)
				(type default)
			)
			(layer "B.Fab")
		)
		(fp_line
			(start 0.8636 0.4572)
			(end 0.8636 0.4064)
			(stroke
				(width 0.1)
				(type default)
			)
			(layer "B.Fab")
		)
		(fp_line
			(start -1.1938 0.4064)
			(end -0.8636 0.4064)
			(stroke
				(width 0.1)
				(type default)
			)
			(layer "B.Fab")
		)
		(fp_line
			(start -0.8636 0.4064)
			(end -0.8636 0.4572)
			(stroke
				(width 0.1)
				(type default)
			)
			(layer "B.Fab")
		)
		(fp_line
			(start 0.8636 0.4064)
			(end 1.1938 0.4064)
			(stroke
				(width 0.1)
				(type default)
			)
			(layer "B.Fab")
		)
		(fp_line
			(start 1.1938 0.4064)
			(end 1.1938 -0.4064)
			(stroke
				(width 0.1)
				(type default)
			)
			(layer "B.Fab")
		)
		(fp_line
			(start -1.1938 -0.4064)
			(end -1.1938 0.4064)
			(stroke
				(width 0.1)
				(type default)
			)
			(layer "B.Fab")
		)
		(fp_line
			(start -0.8636 -0.4064)
			(end -1.1938 -0.4064)
			(stroke
				(width 0.1)
				(type default)
			)
			(layer "B.Fab")
		)
		(fp_line
			(start 0.8636 -0.4064)
			(end 0.8636 -0.4572)
			(stroke
				(width 0.1)
				(type default)
			)
			(layer "B.Fab")
		)
		(fp_line
			(start 1.1938 -0.4064)
			(end 0.8636 -0.4064)
			(stroke
				(width 0.1)
				(type default)
			)
			(layer "B.Fab")
		)
		(fp_line
			(start -0.8636 -0.4572)
			(end -0.8636 -0.4064)
			(stroke
				(width 0.1)
				(type default)
			)
			(layer "B.Fab")
		)
		(fp_line
			(start 0.8636 -0.4572)
			(end -0.8636 -0.4572)
			(stroke
				(width 0.1)
				(type default)
			)
			(layer "B.Fab")
		)
		(pad "1" smd rect
			(at 0.7366 0 180)
			(size 0.7112 0.8128)
			(layers "B.Cu" "B.Mask" "B.Paste")
			(net "P0V8_SERDES_VDDA_PEX3_C4")
		)
		(pad "2" smd rect
			(at -0.7366 0 180)
			(size 0.7112 0.8128)
			(layers "B.Cu" "B.Mask" "B.Paste")
			(net "GND")
		)
	)
	(footprint ""
		(layer "B.Cu")
		(at 228.968046 -138.649202 180)
		(property "Reference" "L80"
			(at 0 0 0)
			(layer "B.SilkS")
			(hide yes)
			(effects
				(font
					(size 1.27 1.27)
				)
				(justify mirror)
			)
		)
		(property "Value" ""
			(at 0 0 0)
			(layer "B.Fab")
			(effects
				(font
					(size 1.27 1.27)
				)
				(justify mirror)
			)
		)
		(duplicate_pad_numbers_are_jumpers no)
		(fp_line
			(start 1.63576 -0.8128)
			(end 1.63576 0.8128)
			(stroke
				(width 0.1524)
				(type default)
			)
			(layer "B.SilkS")
		)
		(fp_line
			(start 1.63576 -0.8128)
			(end -1.63576 -0.8128)
			(stroke
				(width 0.1524)
				(type default)
			)
			(layer "B.SilkS")
		)
		(fp_line
			(start -1.63576 0.8128)
			(end 1.63576 0.8128)
			(stroke
				(width 0.1524)
				(type default)
			)
			(layer "B.SilkS")
		)
		(fp_line
			(start -1.63576 -0.8128)
			(end -1.63576 0.8128)
			(stroke
				(width 0.1524)
				(type default)
			)
			(layer "B.SilkS")
		)
		(fp_line
			(start 1.56083 0.7366)
			(end 1.524 0.7366)
			(stroke
				(width 0.1)
				(type default)
			)
			(layer "B.Fab")
		)
		(fp_line
			(start 1.56083 -0.738632)
			(end 1.56083 0.7366)
			(stroke
				(width 0.1)
				(type default)
			)
			(layer "B.Fab")
		)
		(fp_line
			(start 1.524 0.7366)
			(end -1.524 0.7366)
			(stroke
				(width 0.1)
				(type default)
			)
			(layer "B.Fab")
		)
		(fp_line
			(start -1.524 0.7366)
			(end -1.560576 0.7366)
			(stroke
				(width 0.1)
				(type default)
			)
			(layer "B.Fab")
		)
		(fp_line
			(start -1.560576 0.7366)
			(end -1.560576 -0.738632)
			(stroke
				(width 0.1)
				(type default)
			)
			(layer "B.Fab")
		)
		(fp_line
			(start -1.560576 -0.738632)
			(end 1.56083 -0.738632)
			(stroke
				(width 0.1)
				(type default)
			)
			(layer "B.Fab")
		)
		(pad "1" smd rect
			(at 0.94996 0 180)
			(size 1.1176 1.3716)
			(layers "B.Cu" "B.Mask" "B.Paste")
			(net "P3V3")
		)
		(pad "2" smd rect
			(at -0.94996 0 180)
			(size 1.1176 1.3716)
			(layers "B.Cu" "B.Mask" "B.Paste")
			(net "P3V3_CLK_GEN_VDDXTAL_CK440_PEX")
		)
	)
	(footprint ""
		(layer "B.Cu")
		(at 261.904226 -226.78263 180)
		(property "Reference" "R6168"
			(at 0 0 0)
			(layer "B.SilkS")
			(hide yes)
			(effects
				(font
					(size 1.27 1.27)
				)
				(justify mirror)
			)
		)
		(property "Value" ""
			(at 0 0 0)
			(layer "B.Fab")
			(effects
				(font
					(size 1.27 1.27)
				)
				(justify mirror)
			)
		)
		(duplicate_pad_numbers_are_jumpers no)
		(fp_line
			(start 0.7874 0.4064)
			(end 0.7874 -0.4064)
			(stroke
				(width 0.1524)
				(type default)
			)
			(layer "B.SilkS")
		)
		(fp_line
			(start 0.7874 -0.4064)
			(end -0.7874 -0.4064)
			(stroke
				(width 0.1524)
				(type default)
			)
			(layer "B.SilkS")
		)
		(fp_line
			(start -0.7874 0.4064)
			(end 0.7874 0.4064)
			(stroke
				(width 0.1524)
				(type default)
			)
			(layer "B.SilkS")
		)
		(fp_line
			(start -0.7874 -0.4064)
			(end -0.7874 0.4064)
			(stroke
				(width 0.1524)
				(type default)
			)
			(layer "B.SilkS")
		)
		(fp_line
			(start 0.67945 0.3048)
			(end 0.67945 -0.305054)
			(stroke
				(width 0.1)
				(type default)
			)
			(layer "B.Fab")
		)
		(fp_line
			(start 0.67945 -0.305054)
			(end 0.12065 -0.305054)
			(stroke
				(width 0.1)
				(type default)
			)
			(layer "B.Fab")
		)
		(fp_line
			(start 0.12065 0.3048)
			(end 0.67945 0.3048)
			(stroke
				(width 0.1)
				(type default)
			)
			(layer "B.Fab")
		)
		(fp_line
			(start 0.12065 0.2794)
			(end 0.12065 0.3048)
			(stroke
				(width 0.1)
				(type default)
			)
			(layer "B.Fab")
		)
		(fp_line
			(start 0.12065 -0.2794)
			(end -0.12065 -0.2794)
			(stroke
				(width 0.1)
				(type default)
			)
			(layer "B.Fab")
		)
		(fp_line
			(start 0.12065 -0.305054)
			(end 0.12065 -0.2794)
			(stroke
				(width 0.1)
				(type default)
			)
			(layer "B.Fab")
		)
		(fp_line
			(start -0.120396 0.3048)
			(end -0.120396 0.2794)
			(stroke
				(width 0.1)
				(type default)
			)
			(layer "B.Fab")
		)
		(fp_line
			(start -0.120396 0.2794)
			(end 0.12065 0.2794)
			(stroke
				(width 0.1)
				(type default)
			)
			(layer "B.Fab")
		)
		(fp_line
			(start -0.12065 -0.2794)
			(end -0.12065 -0.3048)
			(stroke
				(width 0.1)
				(type default)
			)
			(layer "B.Fab")
		)
		(fp_line
			(start -0.12065 -0.3048)
			(end -0.67945 -0.3048)
			(stroke
				(width 0.1)
				(type default)
			)
			(layer "B.Fab")
		)
		(fp_line
			(start -0.67945 0.3048)
			(end -0.120396 0.3048)
			(stroke
				(width 0.1)
				(type default)
			)
			(layer "B.Fab")
		)
		(fp_line
			(start -0.67945 -0.3048)
			(end -0.67945 0.3048)
			(stroke
				(width 0.1)
				(type default)
			)
			(layer "B.Fab")
		)
		(pad "1" smd circle
			(at 0.40005 0)
			(size 0 0)
			(layers "B.Cu" "B.Mask" "B.Paste")
			(net "SPI_PEX2_RST_R_N")
		)
		(pad "2" smd circle
			(at -0.40005 0)
			(size 0 0)
			(layers "B.Cu" "B.Mask" "B.Paste")
			(net "SPI_PEX2_RST_N")
		)
	)
	(footprint ""
		(layer "B.Cu")
		(at 49.5554 -151.9936)
		(property "Reference" "R18"
			(at 0 0 0)
			(layer "B.SilkS")
			(hide yes)
			(effects
				(font
					(size 1.27 1.27)
				)
				(justify mirror)
			)
		)
		(property "Value" ""
			(at 0 0 0)
			(layer "B.Fab")
			(effects
				(font
					(size 1.27 1.27)
				)
				(justify mirror)
			)
		)
		(duplicate_pad_numbers_are_jumpers no)
		(fp_line
			(start -0.7874 -0.4064)
			(end -0.7874 0.4064)
			(stroke
				(width 0.1524)
				(type default)
			)
			(layer "B.SilkS")
		)
		(fp_line
			(start -0.7874 0.4064)
			(end 0.7874 0.4064)
			(stroke
				(width 0.1524)
				(type default)
			)
			(layer "B.SilkS")
		)
		(fp_line
			(start 0.7874 -0.4064)
			(end -0.7874 -0.4064)
			(stroke
				(width 0.1524)
				(type default)
			)
			(layer "B.SilkS")
		)
		(fp_line
			(start 0.7874 0.4064)
			(end 0.7874 -0.4064)
			(stroke
				(width 0.1524)
				(type default)
			)
			(layer "B.SilkS")
		)
		(fp_line
			(start -0.67945 -0.3048)
			(end -0.67945 0.3048)
			(stroke
				(width 0.1)
				(type default)
			)
			(layer "B.Fab")
		)
		(fp_line
			(start -0.67945 0.3048)
			(end -0.120396 0.3048)
			(stroke
				(width 0.1)
				(type default)
			)
			(layer "B.Fab")
		)
		(fp_line
			(start -0.12065 -0.3048)
			(end -0.67945 -0.3048)
			(stroke
				(width 0.1)
				(type default)
			)
			(layer "B.Fab")
		)
		(fp_line
			(start -0.12065 -0.2794)
			(end -0.12065 -0.3048)
			(stroke
				(width 0.1)
				(type default)
			)
			(layer "B.Fab")
		)
		(fp_line
			(start -0.120396 0.2794)
			(end 0.12065 0.2794)
			(stroke
				(width 0.1)
				(type default)
			)
			(layer "B.Fab")
		)
		(fp_line
			(start -0.120396 0.3048)
			(end -0.120396 0.2794)
			(stroke
				(width 0.1)
				(type default)
			)
			(layer "B.Fab")
		)
		(fp_line
			(start 0.12065 -0.305054)
			(end 0.12065 -0.2794)
			(stroke
				(width 0.1)
				(type default)
			)
			(layer "B.Fab")
		)
		(fp_line
			(start 0.12065 -0.2794)
			(end -0.12065 -0.2794)
			(stroke
				(width 0.1)
				(type default)
			)
			(layer "B.Fab")
		)
		(fp_line
			(start 0.12065 0.2794)
			(end 0.12065 0.3048)
			(stroke
				(width 0.1)
				(type default)
			)
			(layer "B.Fab")
		)
		(fp_line
			(start 0.12065 0.3048)
			(end 0.67945 0.3048)
			(stroke
				(width 0.1)
				(type default)
			)
			(layer "B.Fab")
		)
		(fp_line
			(start 0.67945 -0.305054)
			(end 0.12065 -0.305054)
			(stroke
				(width 0.1)
				(type default)
			)
			(layer "B.Fab")
		)
		(fp_line
			(start 0.67945 0.3048)
			(end 0.67945 -0.305054)
			(stroke
				(width 0.1)
				(type default)
			)
			(layer "B.Fab")
		)
		(pad "1" smd circle
			(at 0.40005 0 180)
			(size 0 0)
			(layers "B.Cu" "B.Mask" "B.Paste")
			(net "NCSI_NIC0_TXD0")
		)
		(pad "2" smd circle
			(at -0.40005 0 180)
			(size 0 0)
			(layers "B.Cu" "B.Mask" "B.Paste")
			(net "GND")
		)
	)
	(footprint ""
		(layer "B.Cu")
		(at 356.38232 -308.613556 90)
		(property "Reference" "C4375"
			(at 0 0 90)
			(layer "B.SilkS")
			(hide yes)
			(effects
				(font
					(size 1.27 1.27)
				)
				(justify mirror)
			)
		)
		(property "Value" ""
			(at 0 0 90)
			(layer "B.Fab")
			(effects
				(font
					(size 1.27 1.27)
				)
				(justify mirror)
			)
		)
		(duplicate_pad_numbers_are_jumpers no)
		(fp_line
			(start 1.2954 -0.5842)
			(end -1.2954 -0.5842)
			(stroke
				(width 0.1524)
				(type default)
			)
			(layer "B.SilkS")
		)
		(fp_line
			(start -1.2954 -0.5842)
			(end -1.2954 0.5842)
			(stroke
				(width 0.1524)
				(type default)
			)
			(layer "B.SilkS")
		)
		(fp_line
			(start 1.2954 0.5842)
			(end 1.2954 -0.5842)
			(stroke
				(width 0.1524)
				(type default)
			)
			(layer "B.SilkS")
		)
		(fp_line
			(start -1.2954 0.5842)
			(end 1.2954 0.5842)
			(stroke
				(width 0.1524)
				(type default)
			)
			(layer "B.SilkS")
		)
		(fp_line
			(start 0.8636 -0.4572)
			(end -0.8636 -0.4572)
			(stroke
				(width 0.1)
				(type default)
			)
			(layer "B.Fab")
		)
		(fp_line
			(start -0.8636 -0.4572)
			(end -0.8636 -0.4064)
			(stroke
				(width 0.1)
				(type default)
			)
			(layer "B.Fab")
		)
		(fp_line
			(start 1.1938 -0.4064)
			(end 0.8636 -0.4064)
			(stroke
				(width 0.1)
				(type default)
			)
			(layer "B.Fab")
		)
		(fp_line
			(start 0.8636 -0.4064)
			(end 0.8636 -0.4572)
			(stroke
				(width 0.1)
				(type default)
			)
			(layer "B.Fab")
		)
		(fp_line
			(start -0.8636 -0.4064)
			(end -1.1938 -0.4064)
			(stroke
				(width 0.1)
				(type default)
			)
			(layer "B.Fab")
		)
		(fp_line
			(start -1.1938 -0.4064)
			(end -1.1938 0.4064)
			(stroke
				(width 0.1)
				(type default)
			)
			(layer "B.Fab")
		)
		(fp_line
			(start 1.1938 0.4064)
			(end 1.1938 -0.4064)
			(stroke
				(width 0.1)
				(type default)
			)
			(layer "B.Fab")
		)
		(fp_line
			(start 0.8636 0.4064)
			(end 1.1938 0.4064)
			(stroke
				(width 0.1)
				(type default)
			)
			(layer "B.Fab")
		)
		(fp_line
			(start -0.8636 0.4064)
			(end -0.8636 0.4572)
			(stroke
				(width 0.1)
				(type default)
			)
			(layer "B.Fab")
		)
		(fp_line
			(start -1.1938 0.4064)
			(end -0.8636 0.4064)
			(stroke
				(width 0.1)
				(type default)
			)
			(layer "B.Fab")
		)
		(fp_line
			(start 0.8636 0.4572)
			(end 0.8636 0.4064)
			(stroke
				(width 0.1)
				(type default)
			)
			(layer "B.Fab")
		)
		(fp_line
			(start -0.8636 0.4572)
			(end 0.8636 0.4572)
			(stroke
				(width 0.1)
				(type default)
			)
			(layer "B.Fab")
		)
		(pad "1" smd rect
			(at 0.7366 0)
			(size 0.7112 0.8128)
			(layers "B.Cu" "B.Mask" "B.Paste")
			(net "P0V8_PEX3")
		)
		(pad "2" smd rect
			(at -0.7366 0)
			(size 0.7112 0.8128)
			(layers "B.Cu" "B.Mask" "B.Paste")
			(net "GND")
		)
	)
	(footprint ""
		(layer "B.Cu")
		(at 421.700198 -112.604296)
		(property "Reference" "C955"
			(at 0 0 0)
			(layer "B.SilkS")
			(hide yes)
			(effects
				(font
					(size 1.27 1.27)
				)
				(justify mirror)
			)
		)
		(property "Value" ""
			(at 0 0 0)
			(layer "B.Fab")
			(effects
				(font
					(size 1.27 1.27)
				)
				(justify mirror)
			)
		)
		(duplicate_pad_numbers_are_jumpers no)
		(fp_line
			(start -0.299974 -0.150114)
			(end -0.299974 0.150114)
			(stroke
				(width 0.1)
				(type default)
			)
			(layer "B.Fab")
		)
		(fp_line
			(start -0.299974 0.150114)
			(end 0.299974 0.150114)
			(stroke
				(width 0.1)
				(type default)
			)
			(layer "B.Fab")
		)
		(fp_line
			(start 0.299974 -0.150114)
			(end -0.299974 -0.150114)
			(stroke
				(width 0.1)
				(type default)
			)
			(layer "B.Fab")
		)
		(fp_line
			(start 0.299974 0.150114)
			(end 0.299974 -0.150114)
			(stroke
				(width 0.1)
				(type default)
			)
			(layer "B.Fab")
		)
		(pad "1" smd rect
			(at 0.2667 0 180)
			(size 0.3048 0.381)
			(layers "B.Cu" "B.Mask" "B.Paste")
			(net "P12V_NIC7")
		)
		(pad "2" smd rect
			(at -0.2667 0 180)
			(size 0.3048 0.381)
			(layers "B.Cu" "B.Mask" "B.Paste")
			(net "GND")
		)
	)
)
